(kicad_pcb
	(version 20241229)
	(generator "pcbnew")
	(generator_version "9.0")
	(general
		(thickness 1.61)
		(legacy_teardrops no)
	)
	(paper "A3")
	(title_block
		(title "SO-DIMM DDR5 Tester")
		(date "2025-11-26")
		(rev "1.3.0")
		(comment 9 "footprints 269-275 of 627")
	)
	(layers
		(0 "F.Cu" signal)
		(4 "In1.Cu" power)
		(6 "In2.Cu" mixed)
		(8 "In3.Cu" power)
		(10 "In4.Cu" mixed)
		(12 "In5.Cu" power)
		(14 "In6.Cu" mixed)
		(16 "In7.Cu" power)
		(18 "In8.Cu" power)
		(20 "In9.Cu" mixed)
		(22 "In10.Cu" power)
		(2 "B.Cu" signal)
		(9 "F.Adhes" user "F.Adhesive")
		(11 "B.Adhes" user "B.Adhesive")
		(13 "F.Paste" user)
		(15 "B.Paste" user)
		(5 "F.SilkS" user "F.Silkscreen")
		(7 "B.SilkS" user "B.Silkscreen")
		(1 "F.Mask" user)
		(3 "B.Mask" user)
		(17 "Dwgs.User" user "User.Drawings")
		(19 "Cmts.User" user "User.Comments")
		(21 "Eco1.User" user "User.Eco1")
		(23 "Eco2.User" user "User.Eco2")
		(25 "Edge.Cuts" user)
		(27 "Margin" user)
		(31 "F.CrtYd" user "F.Courtyard")
		(29 "B.CrtYd" user "B.Courtyard")
		(35 "F.Fab" user)
		(33 "B.Fab" user)
	)
	(footprint "antmicro-footprints:R_0603_1608Metric"
		(layer "F.Cu")
		(at 166.100501 194.15 180)
		(descr "Resistor SMD 0603")
		(tags "resistor SMD 0603")
		(property "Reference" "R189"
			(at 1.550501 0.9 180)
			(layer "F.SilkS")
			(effects
				(font
					(size 0.7 0.7)
					(thickness 0.15)
				)
				(justify left bottom)
			)
		)
		(property "Value" "R_0R_22.4A_0603"
			(at 0 1.6 180)
			(layer "F.Fab")
			(effects
				(font
					(size 0.7 0.7)
					(thickness 0.15)
				)
				(justify left bottom)
			)
		)
		(property "Datasheet" "https://fscdn.rohm.com/en/products/databook/datasheet/passive/resistor/chip_resistor/pmr-jpw-e.pdf"
			(at 0 0 180)
			(layer "F.Fab")
			(hide yes)
			(effects
				(font
					(size 1.27 1.27)
					(thickness 0.15)
				)
			)
		)
		(property "Author" "Antmicro"
			(at 332.201002 388.3 0)
			(layer "F.Fab")
			(hide yes)
			(effects
				(font
					(size 1 1)
					(thickness 0.15)
				)
			)
		)
		(property "License" "Apache-2.0"
			(at 332.201002 388.3 0)
			(layer "F.Fab")
			(hide yes)
			(effects
				(font
					(size 1 1)
					(thickness 0.15)
				)
			)
		)
		(property "MPN" "PMR03EZPJ000"
			(at 332.201002 388.3 0)
			(layer "F.Fab")
			(hide yes)
			(effects
				(font
					(size 1 1)
					(thickness 0.15)
				)
			)
		)
		(property "Manufacturer" "ROHM Semiconductor"
			(at 332.201002 388.3 0)
			(layer "F.Fab")
			(hide yes)
			(effects
				(font
					(size 1 1)
					(thickness 0.15)
				)
			)
		)
		(property "Max. Curr." "22.4A"
			(at 332.201002 388.3 0)
			(layer "F.Fab")
			(hide yes)
			(effects
				(font
					(size 1 1)
					(thickness 0.15)
				)
			)
		)
		(property "Val" "0R"
			(at 332.201002 388.3 0)
			(layer "F.Fab")
			(hide yes)
			(effects
				(font
					(size 1 1)
					(thickness 0.15)
				)
			)
		)
		(sheetname "/Supply/")
		(sheetfile "supply.kicad_sch")
		(attr smd)
		(fp_line
			(start -0.3 0.3)
			(end 0.3 0.3)
			(stroke
				(width 0.15)
				(type solid)
			)
			(layer "F.SilkS")
		)
		(fp_line
			(start -0.3 -0.3)
			(end 0.3 -0.3)
			(stroke
				(width 0.15)
				(type solid)
			)
			(layer "F.SilkS")
		)
		(fp_rect
			(start -1.25 -0.7)
			(end 1.25 0.7)
			(stroke
				(width 0.05)
				(type solid)
			)
			(fill no)
			(layer "F.CrtYd")
		)
		(fp_rect
			(start -0.8 -0.4)
			(end 0.8 0.4)
			(stroke
				(width 0.15)
				(type solid)
			)
			(fill no)
			(layer "F.Fab")
		)
		(pad "1" smd roundrect
			(at -0.7 0 180)
			(size 0.6 0.8)
			(layers "F.Cu" "F.Mask" "F.Paste")
			(roundrect_rratio 0.2)
			(net 78 "/Supply/1V0_REG")
			(pintype "passive")
		)
		(pad "2" smd roundrect
			(at 0.7 0 180)
			(size 0.6 0.8)
			(layers "F.Cu" "F.Mask" "F.Paste")
			(roundrect_rratio 0.2)
			(net 227 "+1V0")
			(pintype "passive")
		)
	)
	(footprint "antmicro-footprints:SOT-143-4"
		(layer "F.Cu")
		(at 196.5495 142.8135 -90)
		(descr "http://datasheets.maximintegrated.com/en/ds/MAX6816-MAX6818.pdf")
		(property "Reference" "U26"
			(at 1.6865 -2.7505 270)
			(layer "F.SilkS")
			(effects
				(font
					(size 0.7 0.7)
					(thickness 0.15)
				)
				(justify left bottom)
			)
		)
		(property "Value" "MAX812REUS+T"
			(at 0 2.999 270)
			(layer "F.Fab")
			(effects
				(font
					(size 0.7 0.7)
					(thickness 0.15)
				)
				(justify left bottom)
			)
		)
		(property "Datasheet" "https://datasheets.maximintegrated.com/en/ds/MAX811-MAX812T.pdf"
			(at 0 0 270)
			(layer "F.Fab")
			(hide yes)
			(effects
				(font
					(size 1.27 1.27)
					(thickness 0.15)
				)
			)
		)
		(property "Author" "Antmicro"
			(at 53.736 339.363 0)
			(layer "F.Fab")
			(hide yes)
			(effects
				(font
					(size 1 1)
					(thickness 0.15)
				)
			)
		)
		(property "License" "Apache-2.0"
			(at 53.736 339.363 0)
			(layer "F.Fab")
			(hide yes)
			(effects
				(font
					(size 1 1)
					(thickness 0.15)
				)
			)
		)
		(property "MPN" "MAX812REUS+T"
			(at 53.736 339.363 0)
			(layer "F.Fab")
			(hide yes)
			(effects
				(font
					(size 1 1)
					(thickness 0.15)
				)
			)
		)
		(property "Manufacturer" "Maxim Integrated Products"
			(at 53.736 339.363 0)
			(layer "F.Fab")
			(hide yes)
			(effects
				(font
					(size 1 1)
					(thickness 0.15)
				)
			)
		)
		(sheetname "/Supply/")
		(sheetfile "supply.kicad_sch")
		(attr smd)
		(fp_circle
			(center -2.1 1.7)
			(end -2.05 1.7)
			(stroke
				(width 0.15)
				(type solid)
			)
			(fill yes)
			(layer "F.SilkS")
		)
		(fp_rect
			(start -1.776 -1.896)
			(end 1.773 1.895)
			(stroke
				(width 0.05)
				(type solid)
			)
			(fill no)
			(layer "F.CrtYd")
		)
		(fp_line
			(start -1.46 0.65)
			(end 1.459 0.65)
			(stroke
				(width 0.15)
				(type solid)
			)
			(layer "F.Fab")
		)
		(fp_line
			(start -1.46 0.65)
			(end -1.46 -0.652)
			(stroke
				(width 0.15)
				(type solid)
			)
			(layer "F.Fab")
		)
		(fp_line
			(start 1.459 -0.652)
			(end 1.459 0.65)
			(stroke
				(width 0.15)
				(type solid)
			)
			(layer "F.Fab")
		)
		(fp_line
			(start 1.459 -0.652)
			(end -1.46 -0.652)
			(stroke
				(width 0.15)
				(type solid)
			)
			(layer "F.Fab")
		)
		(pad "1" smd roundrect
			(at -0.76 0.998 270)
			(size 0.94 1.31)
			(layers "F.Cu" "F.Mask" "F.Paste")
			(roundrect_rratio 0.25)
			(net 1 "GND")
			(pinfunction "GND")
			(pintype "power_in")
		)
		(pad "2" smd roundrect
			(at 0.959 0.998 270)
			(size 0.55 1.31)
			(layers "F.Cu" "F.Mask" "F.Paste")
			(roundrect_rratio 0.25)
			(net 368 "Net-(Q17-G)")
			(pinfunction "~{RST}")
			(pintype "output")
		)
		(pad "3" smd roundrect
			(at 0.959 -1 270)
			(size 0.55 1.31)
			(layers "F.Cu" "F.Mask" "F.Paste")
			(roundrect_rratio 0.25)
			(net 367 "Net-(Q16-D)")
			(pinfunction "~{MR}")
			(pintype "input")
		)
		(pad "4" smd roundrect
			(at -0.96 -1 270)
			(size 0.55 1.31)
			(layers "F.Cu" "F.Mask" "F.Paste")
			(roundrect_rratio 0.25)
			(net 41 "+3V3_AON")
			(pinfunction "VCC")
			(pintype "power_in")
		)
	)
	(footprint "antmicro-footprints:C_0603_1608Metric"
		(layer "F.Cu")
		(at 168.655502 197.114502 180)
		(descr "Capacitor SMD 0603")
		(tags "capacitor 0603")
		(property "Reference" "C219"
			(at -1.42757 -1.000252 180)
			(layer "F.SilkS")
			(hide yes)
			(effects
				(font
					(size 0.7 0.7)
					(thickness 0.15)
				)
				(justify left bottom)
			)
		)
		(property "Value" "C_22u_0603"
			(at -1.42757 1.770288 180)
			(layer "F.Fab")
			(effects
				(font
					(size 0.7 0.7)
					(thickness 0.15)
				)
				(justify left bottom)
			)
		)
		(property "Datasheet" "https://www.murata.com/products/productdetail?partno=GRM188R60J226MEA0%23"
			(at 0 0 180)
			(layer "F.Fab")
			(hide yes)
			(effects
				(font
					(size 1.27 1.27)
					(thickness 0.15)
				)
			)
		)
		(property "Author" "Antmicro"
			(at 337.311004 394.229004 0)
			(layer "F.Fab")
			(hide yes)
			(effects
				(font
					(size 1 1)
					(thickness 0.15)
				)
			)
		)
		(property "Dielectric" ""
			(at 337.311004 394.229004 0)
			(layer "F.Fab")
			(hide yes)
			(effects
				(font
					(size 1 1)
					(thickness 0.15)
				)
			)
		)
		(property "License" "Apache-2.0"
			(at 337.311004 394.229004 0)
			(layer "F.Fab")
			(hide yes)
			(effects
				(font
					(size 1 1)
					(thickness 0.15)
				)
			)
		)
		(property "MPN" "GRM188R60J226MEA0D"
			(at 337.311004 394.229004 0)
			(layer "F.Fab")
			(hide yes)
			(effects
				(font
					(size 1 1)
					(thickness 0.15)
				)
			)
		)
		(property "Manufacturer" "Murata"
			(at 337.311004 394.229004 0)
			(layer "F.Fab")
			(hide yes)
			(effects
				(font
					(size 1 1)
					(thickness 0.15)
				)
			)
		)
		(property "Val" "22u"
			(at 337.311004 394.229004 0)
			(layer "F.Fab")
			(hide yes)
			(effects
				(font
					(size 1 1)
					(thickness 0.15)
				)
			)
		)
		(property "Voltage" ""
			(at 337.311004 394.229004 0)
			(layer "F.Fab")
			(hide yes)
			(effects
				(font
					(size 1 1)
					(thickness 0.15)
				)
			)
		)
		(sheetname "/Supply/")
		(sheetfile "supply.kicad_sch")
		(attr smd)
		(fp_line
			(start -0.3 0.3)
			(end 0.3 0.3)
			(stroke
				(width 0.15)
				(type solid)
			)
			(layer "F.SilkS")
		)
		(fp_line
			(start -0.3 -0.3)
			(end 0.3 -0.3)
			(stroke
				(width 0.15)
				(type solid)
			)
			(layer "F.SilkS")
		)
		(fp_rect
			(start -1.24 -0.7)
			(end 1.24 0.7)
			(stroke
				(width 0.05)
				(type solid)
			)
			(fill no)
			(layer "F.CrtYd")
		)
		(fp_rect
			(start -0.8 -0.4)
			(end 0.8 0.4)
			(stroke
				(width 0.15)
				(type solid)
			)
			(fill no)
			(layer "F.Fab")
		)
		(pad "1" smd roundrect
			(at -0.7 0 180)
			(size 0.6 0.8)
			(layers "F.Cu" "F.Mask" "F.Paste")
			(roundrect_rratio 0.2)
			(net 1 "GND")
			(pintype "passive")
		)
		(pad "2" smd roundrect
			(at 0.7 0 180)
			(size 0.6 0.8)
			(layers "F.Cu" "F.Mask" "F.Paste")
			(roundrect_rratio 0.2)
			(net 78 "/Supply/1V0_REG")
			(pintype "passive")
		)
	)
	(footprint "antmicro-footprints:R_0402_1005Metric"
		(layer "F.Cu")
		(at 82.010758 182.9281 -90)
		(descr "Resistor SMD 0402")
		(tags "resistor SMD 0402")
		(property "Reference" "R89"
			(at -1.122484 -0.772697 270)
			(layer "F.SilkS")
			(hide yes)
			(effects
				(font
					(size 0.7 0.7)
					(thickness 0.15)
				)
				(justify left bottom)
			)
		)
		(property "Value" "R_330R_0402"
			(at -1.011843 1.772047 270)
			(layer "F.Fab")
			(effects
				(font
					(size 0.7 0.7)
					(thickness 0.15)
				)
				(justify left bottom)
			)
		)
		(property "Datasheet" "https://www.bourns.com/docs/product-datasheets/cr.pdf"
			(at 0 0 270)
			(layer "F.Fab")
			(hide yes)
			(effects
				(font
					(size 1.27 1.27)
					(thickness 0.15)
				)
			)
		)
		(property "Author" "Antmicro"
			(at -100.917342 264.938858 0)
			(layer "F.Fab")
			(hide yes)
			(effects
				(font
					(size 1 1)
					(thickness 0.15)
				)
			)
		)
		(property "License" "Apache-2.0"
			(at -100.917342 264.938858 0)
			(layer "F.Fab")
			(hide yes)
			(effects
				(font
					(size 1 1)
					(thickness 0.15)
				)
			)
		)
		(property "MPN" "CR0402-FX-3300GLF"
			(at -100.917342 264.938858 0)
			(layer "F.Fab")
			(hide yes)
			(effects
				(font
					(size 1 1)
					(thickness 0.15)
				)
			)
		)
		(property "Manufacturer" "Bourns"
			(at -100.917342 264.938858 0)
			(layer "F.Fab")
			(hide yes)
			(effects
				(font
					(size 1 1)
					(thickness 0.15)
				)
			)
		)
		(property "Tolerance" "1%"
			(at -100.917342 264.938858 0)
			(layer "F.Fab")
			(hide yes)
			(effects
				(font
					(size 1 1)
					(thickness 0.15)
				)
			)
		)
		(property "Val" "330R"
			(at -100.917342 264.938858 0)
			(layer "F.Fab")
			(hide yes)
			(effects
				(font
					(size 1 1)
					(thickness 0.15)
				)
			)
		)
		(sheetname "/HDMI + SD Card/")
		(sheetfile "hdmi-sd-card.kicad_sch")
		(attr smd)
		(fp_rect
			(start -0.93 -0.47)
			(end 0.93 0.47)
			(stroke
				(width 0.05)
				(type solid)
			)
			(fill no)
			(layer "F.CrtYd")
		)
		(fp_rect
			(start -0.5 -0.25)
			(end 0.5 0.25)
			(stroke
				(width 0.15)
				(type solid)
			)
			(fill no)
			(layer "F.Fab")
		)
		(pad "1" smd roundrect
			(at -0.485 0 270)
			(size 0.59 0.64)
			(layers "F.Cu" "F.Mask" "F.Paste")
			(roundrect_rratio 0.25)
			(net 1 "GND")
			(pintype "passive")
		)
		(pad "2" smd roundrect
			(at 0.485 0 270)
			(size 0.59 0.64)
			(layers "F.Cu" "F.Mask" "F.Paste")
			(roundrect_rratio 0.25)
			(net 251 "Net-(C132-Pad1)")
			(pintype "passive")
		)
	)
	(footprint "antmicro-footprints:R_0402_1005Metric"
		(layer "F.Cu")
		(at 97.700501 126.735461 -90)
		(descr "Resistor SMD 0402")
		(tags "resistor SMD 0402")
		(property "Reference" "R11"
			(at -1.122484 -0.772697 270)
			(layer "F.SilkS")
			(hide yes)
			(effects
				(font
					(size 0.7 0.7)
					(thickness 0.15)
				)
				(justify left bottom)
			)
		)
		(property "Value" "R_330R_0402"
			(at -1.011843 1.772047 270)
			(layer "F.Fab")
			(effects
				(font
					(size 0.7 0.7)
					(thickness 0.15)
				)
				(justify left bottom)
			)
		)
		(property "Datasheet" "https://www.bourns.com/docs/product-datasheets/cr.pdf"
			(at 0 0 270)
			(layer "F.Fab")
			(hide yes)
			(effects
				(font
					(size 1.27 1.27)
					(thickness 0.15)
				)
			)
		)
		(property "Author" "Antmicro"
			(at -29.03496 224.435962 0)
			(layer "F.Fab")
			(hide yes)
			(effects
				(font
					(size 1 1)
					(thickness 0.15)
				)
			)
		)
		(property "License" "Apache-2.0"
			(at -29.03496 224.435962 0)
			(layer "F.Fab")
			(hide yes)
			(effects
				(font
					(size 1 1)
					(thickness 0.15)
				)
			)
		)
		(property "MPN" "CR0402-FX-3300GLF"
			(at -29.03496 224.435962 0)
			(layer "F.Fab")
			(hide yes)
			(effects
				(font
					(size 1 1)
					(thickness 0.15)
				)
			)
		)
		(property "Manufacturer" "Bourns"
			(at -29.03496 224.435962 0)
			(layer "F.Fab")
			(hide yes)
			(effects
				(font
					(size 1 1)
					(thickness 0.15)
				)
			)
		)
		(property "Tolerance" "1%"
			(at -29.03496 224.435962 0)
			(layer "F.Fab")
			(hide yes)
			(effects
				(font
					(size 1 1)
					(thickness 0.15)
				)
			)
		)
		(property "Val" "330R"
			(at -29.03496 224.435962 0)
			(layer "F.Fab")
			(hide yes)
			(effects
				(font
					(size 1 1)
					(thickness 0.15)
				)
			)
		)
		(sheetname "/FPGA Config/")
		(sheetfile "fpga-config.kicad_sch")
		(attr smd)
		(fp_rect
			(start -0.93 -0.47)
			(end 0.93 0.47)
			(stroke
				(width 0.05)
				(type solid)
			)
			(fill no)
			(layer "F.CrtYd")
		)
		(fp_rect
			(start -0.5 -0.25)
			(end 0.5 0.25)
			(stroke
				(width 0.15)
				(type solid)
			)
			(fill no)
			(layer "F.Fab")
		)
		(pad "1" smd roundrect
			(at -0.485 0 270)
			(size 0.59 0.64)
			(layers "F.Cu" "F.Mask" "F.Paste")
			(roundrect_rratio 0.25)
			(net 304 "Net-(D1-Pad2)")
			(pintype "passive")
		)
		(pad "2" smd roundrect
			(at 0.485 0 270)
			(size 0.59 0.64)
			(layers "F.Cu" "F.Mask" "F.Paste")
			(roundrect_rratio 0.25)
			(net 347 "Net-(Q1-D)")
			(pintype "passive")
		)
	)
	(footprint "antmicro-footprints:C_0603_1608Metric"
		(layer "F.Cu")
		(at 121.8 200.05 180)
		(descr "Capacitor SMD 0603")
		(tags "capacitor 0603")
		(property "Reference" "C180"
			(at -1.42757 -1.000252 180)
			(layer "F.SilkS")
			(hide yes)
			(effects
				(font
					(size 0.7 0.7)
					(thickness 0.15)
				)
				(justify left bottom)
			)
		)
		(property "Value" "C_1u_25V_0603"
			(at -1.42757 1.770288 180)
			(layer "F.Fab")
			(effects
				(font
					(size 0.7 0.7)
					(thickness 0.15)
				)
				(justify left bottom)
			)
		)
		(property "Datasheet" "https://product.samsungsem.com/mlcc/CL10A105KA8NNN.do"
			(at 0 0 180)
			(layer "F.Fab")
			(hide yes)
			(effects
				(font
					(size 1.27 1.27)
					(thickness 0.15)
				)
			)
		)
		(property "Author" "Antmicro"
			(at 243.6 400.1 0)
			(layer "F.Fab")
			(hide yes)
			(effects
				(font
					(size 1 1)
					(thickness 0.15)
				)
			)
		)
		(property "Dielectric" ""
			(at 243.6 400.1 0)
			(layer "F.Fab")
			(hide yes)
			(effects
				(font
					(size 1 1)
					(thickness 0.15)
				)
			)
		)
		(property "License" "Apache-2.0"
			(at 243.6 400.1 0)
			(layer "F.Fab")
			(hide yes)
			(effects
				(font
					(size 1 1)
					(thickness 0.15)
				)
			)
		)
		(property "MPN" "CL10A105KA8NNNC"
			(at 243.6 400.1 0)
			(layer "F.Fab")
			(hide yes)
			(effects
				(font
					(size 1 1)
					(thickness 0.15)
				)
			)
		)
		(property "Manufacturer" "Samsung Electro-Mechanics"
			(at 243.6 400.1 0)
			(layer "F.Fab")
			(hide yes)
			(effects
				(font
					(size 1 1)
					(thickness 0.15)
				)
			)
		)
		(property "Val" "1u/25V"
			(at 243.6 400.1 0)
			(layer "F.Fab")
			(hide yes)
			(effects
				(font
					(size 1 1)
					(thickness 0.15)
				)
			)
		)
		(property "Voltage" ""
			(at 243.6 400.1 0)
			(layer "F.Fab")
			(hide yes)
			(effects
				(font
					(size 1 1)
					(thickness 0.15)
				)
			)
		)
		(sheetname "/Supply/")
		(sheetfile "supply.kicad_sch")
		(attr smd)
		(fp_line
			(start -0.3 0.3)
			(end 0.3 0.3)
			(stroke
				(width 0.15)
				(type solid)
			)
			(layer "F.SilkS")
		)
		(fp_line
			(start -0.3 -0.3)
			(end 0.3 -0.3)
			(stroke
				(width 0.15)
				(type solid)
			)
			(layer "F.SilkS")
		)
		(fp_rect
			(start -1.24 -0.7)
			(end 1.24 0.7)
			(stroke
				(width 0.05)
				(type solid)
			)
			(fill no)
			(layer "F.CrtYd")
		)
		(fp_rect
			(start -0.8 -0.4)
			(end 0.8 0.4)
			(stroke
				(width 0.15)
				(type solid)
			)
			(fill no)
			(layer "F.Fab")
		)
		(pad "1" smd roundrect
			(at -0.7 0 180)
			(size 0.6 0.8)
			(layers "F.Cu" "F.Mask" "F.Paste")
			(roundrect_rratio 0.2)
			(net 1 "GND")
			(pintype "passive")
		)
		(pad "2" smd roundrect
			(at 0.7 0 180)
			(size 0.6 0.8)
			(layers "F.Cu" "F.Mask" "F.Paste")
			(roundrect_rratio 0.2)
			(net 38 "VDC")
			(pintype "passive")
		)
	)
	(footprint "antmicro-footprints:TP_SMD_1mm"
		(layer "F.Cu")
		(at 186.4 173.5)
		(property "Reference" "TP9"
			(at 0 -0.731898 0)
			(layer "F.SilkS")
			(hide yes)
			(effects
				(font
					(size 0.7 0.7)
					(thickness 0.15)
				)
				(justify left bottom)
			)
		)
		(property "Value" "TP_1mm_SMD"
			(at 0 1.4 0)
			(layer "F.Fab")
			(effects
				(font
					(size 0.7 0.7)
					(thickness 0.15)
				)
				(justify left bottom)
			)
		)
		(property "Author" "Antmicro"
			(at 0 0 0)
			(layer "F.Fab")
			(hide yes)
			(effects
				(font
					(size 1 1)
					(thickness 0.15)
				)
			)
		)
		(property "License" "Apache-2.0"
			(at 0 0 0)
			(layer "F.Fab")
			(hide yes)
			(effects
				(font
					(size 1 1)
					(thickness 0.15)
				)
			)
		)
		(property "MPN" ""
			(at 0 0 0)
			(layer "F.Fab")
			(hide yes)
			(effects
				(font
					(size 1 1)
					(thickness 0.15)
				)
			)
		)
		(property "Manufacturer" ""
			(at 0 0 0)
			(layer "F.Fab")
			(hide yes)
			(effects
				(font
					(size 1 1)
					(thickness 0.15)
				)
			)
		)
		(sheetname "/Supply/")
		(sheetfile "supply.kicad_sch")
		(attr exclude_from_pos_files)
		(pad "1" smd circle
			(at 0 0)
			(size 1 1)
			(layers "F.Cu" "F.Mask")
			(net 199 "+1V2")
			(pinfunction "1")
			(pintype "passive")
		)
	)
)
